G04 ================== begin FILE IDENTIFICATION RECORD ==================*
G04 Layout Name:  D:/<user>/Wistron_project/16369-sd/gbr/16369-sd.brd*
G04 Film Name:    SE_REF_L4*
G04 File Format:  Gerber RS274X*
G04 File Origin:  Cadence Allegro 16.5-S056*
G04 Origin Date:  Wed Mar 29 13:12:58 2017*
G04 *
G04 Layer:  BOARD GEOMETRY/SE_REF_L4_TBL*
G04 Layer:  BOARD GEOMETRY/SE_REF_L4_BOTTOM*
G04 Layer:  BOARD GEOMETRY/PANEL_OUTLINE*
G04 *
G04 Offset:    (0.00 0.00)*
G04 Mirror:    No*
G04 Mode:      Positive*
G04 Rotation:  0*
G04 FullContactRelief:  No*
G04 UndefLineWidth:     6.00*
G04 ================== end FILE IDENTIFICATION RECORD ====================*
%FSLAX35Y35*MOIN*%
%IR0*IPPOS*OFA0.00000B0.00000*MIA0B0*SFA1.00000B1.00000*%
%ADD10C,.02*%
%ADD11C,.006*%
%ADD12C,.00675*%
G75*
%LPD*%
G75*
G54D10*
G01X562899Y673913D02*
X1280399D01*
G01X562899Y639263D02*
X1280399D01*
G01X562899Y708563D02*
Y639263D01*
G01Y708563D02*
X1280399D01*
G01X737899D02*
Y639263D01*
G01X965399Y708563D02*
Y639263D01*
G01X1070399Y708563D02*
Y639263D01*
G01X1280399Y708563D02*
Y639263D01*
G54D11*
G01X-25246Y-59178D02*
Y-76678D01*
G01X-30268Y-59178D02*
X-20224D01*
G01X-11458Y-76678D02*
Y-59178D01*
G01Y-67636D02*
X-10366Y-66178D01*
X-9274Y-65303D01*
X-7528Y-65012D01*
X-6218Y-65303D01*
X-4689Y-66470D01*
X-4034Y-68220D01*
Y-76678D01*
G01X9754Y-65012D02*
Y-76678D01*
G01Y-60345D02*
X9317Y-60053D01*
Y-59470D01*
X9754Y-59178D01*
X10191Y-59470D01*
Y-60053D01*
X9754Y-60345D01*
G01X23979Y-74637D02*
X25071Y-75803D01*
X26599Y-76678D01*
X27909D01*
X29219Y-76095D01*
X30092Y-75220D01*
X30529Y-74054D01*
X30311Y-72303D01*
X29437Y-71428D01*
X25507Y-69678D01*
X24634Y-67636D01*
X25071Y-66178D01*
X25944Y-65303D01*
X27254Y-65012D01*
X28564Y-65303D01*
X29874Y-66178D01*
G01X59197Y-81053D02*
X60726Y-82220D01*
X62472Y-82511D01*
X64000Y-82220D01*
X65311Y-80762D01*
X66184Y-78720D01*
Y-65012D01*
G01Y-67345D02*
X65311Y-66178D01*
X64000Y-65303D01*
X62472Y-65012D01*
X60726Y-65595D01*
X59634Y-66761D01*
X58760Y-68803D01*
X58324Y-70845D01*
X58542Y-72595D01*
X59416Y-74637D01*
X60726Y-76095D01*
X62472Y-76678D01*
X63782Y-76386D01*
X65311Y-75220D01*
X66184Y-74054D01*
G01X76479Y-68803D02*
X83466D01*
X82811Y-66761D01*
X81719Y-65595D01*
X80191Y-65012D01*
X78662Y-65303D01*
X77352Y-66178D01*
X76479Y-68220D01*
X76042Y-69970D01*
Y-71720D01*
X76479Y-73470D01*
X77571Y-75220D01*
X78881Y-76386D01*
X80409Y-76678D01*
X81937Y-76095D01*
X83466Y-74345D01*
G01X94197Y-76678D02*
Y-65012D01*
G01Y-67345D02*
X95289Y-66178D01*
X96381Y-65303D01*
X97909Y-65012D01*
X99000Y-65303D01*
X100311Y-66178D01*
G01X110824Y-76678D02*
Y-59178D01*
G01Y-67928D02*
X111916Y-66178D01*
X113226Y-65303D01*
X114536Y-65012D01*
X116500Y-65595D01*
X117811Y-66761D01*
X118684Y-68803D01*
Y-71136D01*
X118247Y-73470D01*
X117374Y-75220D01*
X115846Y-76386D01*
X114536Y-76678D01*
X113226Y-76386D01*
X111916Y-75512D01*
X110824Y-74054D01*
G01X128979Y-68803D02*
X135966D01*
X135311Y-66761D01*
X134219Y-65595D01*
X132691Y-65012D01*
X131162Y-65303D01*
X129852Y-66178D01*
X128979Y-68220D01*
X128542Y-69970D01*
Y-71720D01*
X128979Y-73470D01*
X130071Y-75220D01*
X131381Y-76386D01*
X132909Y-76678D01*
X134437Y-76095D01*
X135966Y-74345D01*
G01X146697Y-76678D02*
Y-65012D01*
G01Y-67345D02*
X147789Y-66178D01*
X148881Y-65303D01*
X150409Y-65012D01*
X151500Y-65303D01*
X152811Y-66178D01*
G01X184754Y-65012D02*
Y-76678D01*
G01Y-60345D02*
X184317Y-60053D01*
Y-59470D01*
X184754Y-59178D01*
X185191Y-59470D01*
Y-60053D01*
X184754Y-60345D01*
G01X198979Y-74637D02*
X200071Y-75803D01*
X201599Y-76678D01*
X202909D01*
X204219Y-76095D01*
X205092Y-75220D01*
X205529Y-74054D01*
X205311Y-72303D01*
X204437Y-71428D01*
X200507Y-69678D01*
X199634Y-67636D01*
X200071Y-66178D01*
X200944Y-65303D01*
X202254Y-65012D01*
X203564Y-65303D01*
X204874Y-66178D01*
G01X233760Y-81053D02*
X235289Y-82220D01*
X236599Y-82511D01*
X238346Y-81928D01*
X239656Y-80470D01*
X240311Y-77844D01*
Y-65012D01*
G01Y-60345D02*
X239874Y-60053D01*
Y-59470D01*
X240311Y-59178D01*
X240747Y-59470D01*
Y-60053D01*
X240311Y-60345D01*
G01X251042Y-65012D02*
Y-73178D01*
X251916Y-75220D01*
X253226Y-76386D01*
X254754Y-76678D01*
X256282Y-76386D01*
X257592Y-75220D01*
X258466Y-73178D01*
G01Y-76678D02*
Y-65012D01*
G01X268979Y-74637D02*
X270071Y-75803D01*
X271599Y-76678D01*
X272909D01*
X274219Y-76095D01*
X275092Y-75220D01*
X275529Y-74054D01*
X275311Y-72303D01*
X274437Y-71428D01*
X270507Y-69678D01*
X269634Y-67636D01*
X270071Y-66178D01*
X270944Y-65303D01*
X272254Y-65012D01*
X273564Y-65303D01*
X274874Y-66178D01*
G01X289754Y-59178D02*
Y-76678D01*
G01X286697Y-65012D02*
X292811D01*
G01X323444Y-76678D02*
Y-61803D01*
X323881Y-60345D01*
X324754Y-59470D01*
X326064Y-59178D01*
X327374Y-59761D01*
X328029Y-61220D01*
G01X325409Y-66178D02*
X321042D01*
G01X342254Y-76678D02*
X340944Y-76386D01*
X339634Y-75220D01*
X338760Y-73178D01*
X338324Y-70845D01*
X338760Y-68511D01*
X339634Y-66470D01*
X340944Y-65303D01*
X342254Y-65012D01*
X343564Y-65303D01*
X344874Y-66470D01*
X345747Y-68511D01*
X345966Y-70845D01*
X345747Y-73178D01*
X344874Y-75220D01*
X343564Y-76386D01*
X342254Y-76678D01*
G01X356697D02*
Y-65012D01*
G01Y-67345D02*
X357789Y-66178D01*
X358881Y-65303D01*
X360409Y-65012D01*
X361500Y-65303D01*
X362811Y-66178D01*
G01X390169Y-81928D02*
X391479Y-82511D01*
X393226Y-81928D01*
X394317Y-80762D01*
X395191Y-79303D01*
X396500Y-74637D01*
X399339Y-65012D01*
G01X392352D02*
X396500Y-74637D01*
G01X412254Y-76678D02*
X410944Y-76386D01*
X409634Y-75220D01*
X408760Y-73178D01*
X408324Y-70845D01*
X408760Y-68511D01*
X409634Y-66470D01*
X410944Y-65303D01*
X412254Y-65012D01*
X413564Y-65303D01*
X414874Y-66470D01*
X415747Y-68511D01*
X415966Y-70845D01*
X415747Y-73178D01*
X414874Y-75220D01*
X413564Y-76386D01*
X412254Y-76678D01*
G01X426042Y-65012D02*
Y-73178D01*
X426916Y-75220D01*
X428226Y-76386D01*
X429754Y-76678D01*
X431282Y-76386D01*
X432592Y-75220D01*
X433466Y-73178D01*
G01Y-76678D02*
Y-65012D01*
G01X444197Y-76678D02*
Y-65012D01*
G01Y-67345D02*
X445289Y-66178D01*
X446381Y-65303D01*
X447909Y-65012D01*
X449000Y-65303D01*
X450311Y-66178D01*
G01X479197Y-76678D02*
Y-65012D01*
G01Y-67345D02*
X480289Y-66178D01*
X481381Y-65303D01*
X482909Y-65012D01*
X484000Y-65303D01*
X485311Y-66178D01*
G01X496479Y-68803D02*
X503466D01*
X502811Y-66761D01*
X501719Y-65595D01*
X500191Y-65012D01*
X498662Y-65303D01*
X497352Y-66178D01*
X496479Y-68220D01*
X496042Y-69970D01*
Y-71720D01*
X496479Y-73470D01*
X497571Y-75220D01*
X498881Y-76386D01*
X500409Y-76678D01*
X501937Y-76095D01*
X503466Y-74345D01*
G01X515944Y-76678D02*
Y-61803D01*
X516381Y-60345D01*
X517254Y-59470D01*
X518564Y-59178D01*
X519874Y-59761D01*
X520529Y-61220D01*
G01X517909Y-66178D02*
X513542D01*
G01X531479Y-68803D02*
X538466D01*
X537811Y-66761D01*
X536719Y-65595D01*
X535191Y-65012D01*
X533662Y-65303D01*
X532352Y-66178D01*
X531479Y-68220D01*
X531042Y-69970D01*
Y-71720D01*
X531479Y-73470D01*
X532571Y-75220D01*
X533881Y-76386D01*
X535409Y-76678D01*
X536937Y-76095D01*
X538466Y-74345D01*
G01X549197Y-76678D02*
Y-65012D01*
G01Y-67345D02*
X550289Y-66178D01*
X551381Y-65303D01*
X552909Y-65012D01*
X554000Y-65303D01*
X555311Y-66178D01*
G01X566479Y-68803D02*
X573466D01*
X572811Y-66761D01*
X571719Y-65595D01*
X570191Y-65012D01*
X568662Y-65303D01*
X567352Y-66178D01*
X566479Y-68220D01*
X566042Y-69970D01*
Y-71720D01*
X566479Y-73470D01*
X567571Y-75220D01*
X568881Y-76386D01*
X570409Y-76678D01*
X571937Y-76095D01*
X573466Y-74345D01*
G01X583542Y-76678D02*
Y-65012D01*
G01Y-67928D02*
X584416Y-66470D01*
X585726Y-65303D01*
X587472Y-65012D01*
X589000Y-65303D01*
X590311Y-66470D01*
X590966Y-68511D01*
Y-76678D01*
G01X608247Y-66470D02*
X606719Y-65303D01*
X605409Y-65012D01*
X603662Y-65595D01*
X602352Y-66761D01*
X601479Y-68803D01*
X601260Y-70845D01*
X601479Y-72887D01*
X602352Y-74637D01*
X603662Y-76095D01*
X605409Y-76678D01*
X606937Y-76095D01*
X608247Y-74928D01*
G01X618979Y-68803D02*
X625966D01*
X625311Y-66761D01*
X624219Y-65595D01*
X622691Y-65012D01*
X621162Y-65303D01*
X619852Y-66178D01*
X618979Y-68220D01*
X618542Y-69970D01*
Y-71720D01*
X618979Y-73470D01*
X620071Y-75220D01*
X621381Y-76386D01*
X622909Y-76678D01*
X624437Y-76095D01*
X625966Y-74345D01*
G01X657254Y-59178D02*
Y-76678D01*
G01X654197Y-65012D02*
X660311D01*
G01X674754Y-76678D02*
X673444Y-76386D01*
X672134Y-75220D01*
X671260Y-73178D01*
X670824Y-70845D01*
X671260Y-68511D01*
X672134Y-66470D01*
X673444Y-65303D01*
X674754Y-65012D01*
X676064Y-65303D01*
X677374Y-66470D01*
X678247Y-68511D01*
X678466Y-70845D01*
X678247Y-73178D01*
X677374Y-75220D01*
X676064Y-76386D01*
X674754Y-76678D01*
G01X708444D02*
Y-61803D01*
X708881Y-60345D01*
X709754Y-59470D01*
X711064Y-59178D01*
X712374Y-59761D01*
X713029Y-61220D01*
G01X710409Y-66178D02*
X706042D01*
G01X727254Y-65012D02*
Y-76678D01*
G01Y-60345D02*
X726817Y-60053D01*
Y-59470D01*
X727254Y-59178D01*
X727691Y-59470D01*
Y-60053D01*
X727254Y-60345D01*
G01X741042Y-76678D02*
Y-65012D01*
G01Y-67928D02*
X741916Y-66470D01*
X743226Y-65303D01*
X744972Y-65012D01*
X746500Y-65303D01*
X747811Y-66470D01*
X748466Y-68511D01*
Y-76678D01*
G01X766184Y-59178D02*
Y-76678D01*
G01Y-74054D02*
X765311Y-75512D01*
X764000Y-76386D01*
X762472Y-76678D01*
X760726Y-76095D01*
X759416Y-74637D01*
X758542Y-72887D01*
X758324Y-70845D01*
X758542Y-68803D01*
X759416Y-67053D01*
X760726Y-65595D01*
X762472Y-65012D01*
X764000Y-65303D01*
X765092Y-65887D01*
X766184Y-67053D01*
G01X797254Y-59178D02*
Y-76678D01*
G01X794197Y-65012D02*
X800311D01*
G01X811042Y-76678D02*
Y-59178D01*
G01Y-67636D02*
X812134Y-66178D01*
X813226Y-65303D01*
X814972Y-65012D01*
X816282Y-65303D01*
X817811Y-66470D01*
X818466Y-68220D01*
Y-76678D01*
G01X828979Y-68803D02*
X835966D01*
X835311Y-66761D01*
X834219Y-65595D01*
X832691Y-65012D01*
X831162Y-65303D01*
X829852Y-66178D01*
X828979Y-68220D01*
X828542Y-69970D01*
Y-71720D01*
X828979Y-73470D01*
X830071Y-75220D01*
X831381Y-76386D01*
X832909Y-76678D01*
X834437Y-76095D01*
X835966Y-74345D01*
G01X862669D02*
X864416Y-75803D01*
X866381Y-76678D01*
X868127D01*
X869874Y-75803D01*
X871184Y-74345D01*
X871839Y-72303D01*
X871402Y-70262D01*
X870311Y-68511D01*
X868346Y-67345D01*
X865726Y-66761D01*
X864197Y-65595D01*
X863542Y-63553D01*
X863979Y-61511D01*
X865071Y-60053D01*
X866599Y-59178D01*
X868127D01*
X869656Y-59761D01*
X870966Y-61220D01*
G01X889121Y-76678D02*
X880387D01*
Y-59178D01*
X889121D01*
G01X885627Y-67636D02*
X880387D01*
G01X919754Y-65012D02*
Y-76678D01*
G01Y-60345D02*
X919317Y-60053D01*
Y-59470D01*
X919754Y-59178D01*
X920191Y-59470D01*
Y-60053D01*
X919754Y-60345D01*
G01X930704Y-76678D02*
Y-65012D01*
G01Y-68220D02*
X931359Y-66761D01*
X932451Y-65595D01*
X933979Y-65012D01*
X935507Y-65595D01*
X936599Y-66761D01*
X937254Y-68220D01*
Y-76678D01*
G01Y-68220D02*
X937909Y-66761D01*
X939000Y-65595D01*
X940529Y-65012D01*
X942057Y-65595D01*
X943149Y-66761D01*
X943804Y-68511D01*
Y-76678D01*
G01X950824Y-82511D02*
Y-65012D01*
G01Y-67636D02*
X951916Y-66178D01*
X953007Y-65303D01*
X954754Y-65012D01*
X956282Y-65303D01*
X957811Y-66761D01*
X958466Y-68803D01*
X958684Y-70845D01*
X958466Y-72887D01*
X957811Y-74928D01*
X956500Y-76095D01*
X954754Y-76678D01*
X953226Y-76386D01*
X951697Y-75512D01*
X950824Y-74345D01*
G01X968979Y-68803D02*
X975966D01*
X975311Y-66761D01*
X974219Y-65595D01*
X972691Y-65012D01*
X971162Y-65303D01*
X969852Y-66178D01*
X968979Y-68220D01*
X968542Y-69970D01*
Y-71720D01*
X968979Y-73470D01*
X970071Y-75220D01*
X971381Y-76386D01*
X972909Y-76678D01*
X974437Y-76095D01*
X975966Y-74345D01*
G01X993684Y-59178D02*
Y-76678D01*
G01Y-74054D02*
X992811Y-75512D01*
X991500Y-76386D01*
X989972Y-76678D01*
X988226Y-76095D01*
X986916Y-74637D01*
X986042Y-72887D01*
X985824Y-70845D01*
X986042Y-68803D01*
X986916Y-67053D01*
X988226Y-65595D01*
X989972Y-65012D01*
X991500Y-65303D01*
X992592Y-65887D01*
X993684Y-67053D01*
G01X1011184Y-76678D02*
Y-65012D01*
G01Y-67053D02*
X1010311Y-65887D01*
X1009000Y-65303D01*
X1007472Y-65012D01*
X1005944Y-65595D01*
X1004634Y-66761D01*
X1003760Y-68511D01*
X1003324Y-70845D01*
X1003760Y-73178D01*
X1004634Y-74928D01*
X1005944Y-76095D01*
X1007472Y-76678D01*
X1009000Y-76386D01*
X1010311Y-75512D01*
X1011184Y-74345D01*
G01X1021042Y-76678D02*
Y-65012D01*
G01Y-67928D02*
X1021916Y-66470D01*
X1023226Y-65303D01*
X1024972Y-65012D01*
X1026500Y-65303D01*
X1027811Y-66470D01*
X1028466Y-68511D01*
Y-76678D01*
G01X1045747Y-66470D02*
X1044219Y-65303D01*
X1042909Y-65012D01*
X1041162Y-65595D01*
X1039852Y-66761D01*
X1038979Y-68803D01*
X1038760Y-70845D01*
X1038979Y-72887D01*
X1039852Y-74637D01*
X1041162Y-76095D01*
X1042909Y-76678D01*
X1044437Y-76095D01*
X1045747Y-74928D01*
G01X1056479Y-68803D02*
X1063466D01*
X1062811Y-66761D01*
X1061719Y-65595D01*
X1060191Y-65012D01*
X1058662Y-65303D01*
X1057352Y-66178D01*
X1056479Y-68220D01*
X1056042Y-69970D01*
Y-71720D01*
X1056479Y-73470D01*
X1057571Y-75220D01*
X1058881Y-76386D01*
X1060409Y-76678D01*
X1061937Y-76095D01*
X1063466Y-74345D01*
G01X1094754Y-59178D02*
Y-76678D01*
G01X1091697Y-65012D02*
X1097811D01*
G01X1109197Y-76678D02*
Y-65012D01*
G01Y-67345D02*
X1110289Y-66178D01*
X1111381Y-65303D01*
X1112909Y-65012D01*
X1114000Y-65303D01*
X1115311Y-66178D01*
G01X1133684Y-76678D02*
Y-65012D01*
G01Y-67053D02*
X1132811Y-65887D01*
X1131500Y-65303D01*
X1129972Y-65012D01*
X1128444Y-65595D01*
X1127134Y-66761D01*
X1126260Y-68511D01*
X1125824Y-70845D01*
X1126260Y-73178D01*
X1127134Y-74928D01*
X1128444Y-76095D01*
X1129972Y-76678D01*
X1131500Y-76386D01*
X1132811Y-75512D01*
X1133684Y-74345D01*
G01X1150747Y-66470D02*
X1149219Y-65303D01*
X1147909Y-65012D01*
X1146162Y-65595D01*
X1144852Y-66761D01*
X1143979Y-68803D01*
X1143760Y-70845D01*
X1143979Y-72887D01*
X1144852Y-74637D01*
X1146162Y-76095D01*
X1147909Y-76678D01*
X1149437Y-76095D01*
X1150747Y-74928D01*
G01X1161479Y-68803D02*
X1168466D01*
X1167811Y-66761D01*
X1166719Y-65595D01*
X1165191Y-65012D01*
X1163662Y-65303D01*
X1162352Y-66178D01*
X1161479Y-68220D01*
X1161042Y-69970D01*
Y-71720D01*
X1161479Y-73470D01*
X1162571Y-75220D01*
X1163881Y-76386D01*
X1165409Y-76678D01*
X1166937Y-76095D01*
X1168466Y-74345D01*
G01X1178979Y-74637D02*
X1180071Y-75803D01*
X1181599Y-76678D01*
X1182909D01*
X1184219Y-76095D01*
X1185092Y-75220D01*
X1185529Y-74054D01*
X1185311Y-72303D01*
X1184437Y-71428D01*
X1180507Y-69678D01*
X1179634Y-67636D01*
X1180071Y-66178D01*
X1180944Y-65303D01*
X1182254Y-65012D01*
X1183564Y-65303D01*
X1184874Y-66178D01*
G01X1217254Y-65012D02*
Y-76678D01*
G01Y-60345D02*
X1216817Y-60053D01*
Y-59470D01*
X1217254Y-59178D01*
X1217691Y-59470D01*
Y-60053D01*
X1217254Y-60345D01*
G01X1231042Y-76678D02*
Y-65012D01*
G01Y-67928D02*
X1231916Y-66470D01*
X1233226Y-65303D01*
X1234972Y-65012D01*
X1236500Y-65303D01*
X1237811Y-66470D01*
X1238466Y-68511D01*
Y-76678D01*
G01X1269754D02*
Y-59178D01*
G01X1291184Y-76678D02*
Y-65012D01*
G01Y-67053D02*
X1290311Y-65887D01*
X1289000Y-65303D01*
X1287472Y-65012D01*
X1285944Y-65595D01*
X1284634Y-66761D01*
X1283760Y-68511D01*
X1283324Y-70845D01*
X1283760Y-73178D01*
X1284634Y-74928D01*
X1285944Y-76095D01*
X1287472Y-76678D01*
X1289000Y-76386D01*
X1290311Y-75512D01*
X1291184Y-74345D01*
G01X1300169Y-81928D02*
X1301479Y-82511D01*
X1303226Y-81928D01*
X1304317Y-80762D01*
X1305191Y-79303D01*
X1306500Y-74637D01*
X1309339Y-65012D01*
G01X1302352D02*
X1306500Y-74637D01*
G01X1318979Y-68803D02*
X1325966D01*
X1325311Y-66761D01*
X1324219Y-65595D01*
X1322691Y-65012D01*
X1321162Y-65303D01*
X1319852Y-66178D01*
X1318979Y-68220D01*
X1318542Y-69970D01*
Y-71720D01*
X1318979Y-73470D01*
X1320071Y-75220D01*
X1321381Y-76386D01*
X1322909Y-76678D01*
X1324437Y-76095D01*
X1325966Y-74345D01*
G01X1336697Y-76678D02*
Y-65012D01*
G01Y-67345D02*
X1337789Y-66178D01*
X1338881Y-65303D01*
X1340409Y-65012D01*
X1341500Y-65303D01*
X1342811Y-66178D01*
G01X1370387Y-59178D02*
Y-76678D01*
X1379121D01*
G01X1394874D02*
Y-59178D01*
X1386795Y-71720D01*
X1397713D01*
G01X1409754Y-77261D02*
X1409317Y-76970D01*
Y-76386D01*
X1409754Y-76095D01*
X1410191Y-76386D01*
Y-76970D01*
X1409754Y-77261D01*
G01X564864Y720646D02*
X566611Y719188D01*
X568576Y718313D01*
X570322D01*
X572069Y719188D01*
X573379Y720646D01*
X574034Y722688D01*
X573597Y724729D01*
X572506Y726480D01*
X570541Y727646D01*
X567921Y728230D01*
X566392Y729396D01*
X565737Y731438D01*
X566174Y733480D01*
X567266Y734938D01*
X568794Y735813D01*
X570322D01*
X571851Y735230D01*
X573161Y733771D01*
G01X591316Y718313D02*
X582582D01*
Y735813D01*
X591316D01*
G01X587822Y727355D02*
X582582D01*
G01X619329Y735813D02*
X624569D01*
G01X621949D02*
Y718313D01*
G01X619329D02*
X624569D01*
G01X633772D02*
Y735813D01*
X639449Y721230D01*
X645126Y735813D01*
Y718313D01*
G01X652582D02*
Y735813D01*
X657822D01*
X659569Y734938D01*
X660879Y732896D01*
X661316Y730563D01*
X660879Y728230D01*
X659787Y726480D01*
X657822Y725604D01*
X652582D01*
G01X678816Y718313D02*
X670082D01*
Y735813D01*
X678816D01*
G01X675322Y727355D02*
X670082D01*
G01X687146Y718313D02*
Y735813D01*
X691512D01*
X693259Y734938D01*
X694569Y733771D01*
X695661Y732022D01*
X696534Y729979D01*
X696752Y727063D01*
X696534Y724146D01*
X695661Y722104D01*
X694569Y720354D01*
X693259Y719188D01*
X691512Y718313D01*
X687146D01*
G01X703990D02*
X709449Y735813D01*
X714908Y718313D01*
G01X712942Y724438D02*
X705955D01*
G01X721927Y718313D02*
Y735813D01*
X731971Y718313D01*
Y735813D01*
G01X749252Y734354D02*
X747942Y735230D01*
X746414Y735813D01*
X744667D01*
X742702Y734938D01*
X741174Y733480D01*
X740082Y731729D01*
X739209Y728813D01*
X738990Y726188D01*
X739427Y723563D01*
X740082Y721813D01*
X741392Y720063D01*
X742921Y718896D01*
X744449Y718313D01*
X745977D01*
X747506Y718896D01*
X748816Y719771D01*
X749908Y720937D01*
G01X766316Y718313D02*
X757582D01*
Y735813D01*
X766316D01*
G01X762822Y727355D02*
X757582D01*
G01X796949Y735813D02*
Y718313D01*
G01X791927Y735813D02*
X801971D01*
G01X808990Y718313D02*
X814449Y735813D01*
X819908Y718313D01*
G01X817942Y724438D02*
X810955D01*
G01X833695Y727646D02*
X834569Y728521D01*
X835224Y729979D01*
X835661Y732022D01*
X835224Y733771D01*
X834351Y734938D01*
X832822Y735813D01*
X826927D01*
Y718313D01*
X834132D01*
X835661Y719479D01*
X836534Y721230D01*
X836971Y723271D01*
X836534Y725313D01*
X835224Y727063D01*
X833695Y727646D01*
X826927D01*
G01X845082Y735813D02*
Y718313D01*
X853816D01*
G01X871316D02*
X862582D01*
Y735813D01*
X871316D01*
G01X867822Y727355D02*
X862582D01*
G01X884449Y717730D02*
X884012Y718021D01*
Y718605D01*
X884449Y718896D01*
X884886Y718605D01*
Y718021D01*
X884449Y717730D01*
G01Y725604D02*
X884012Y725896D01*
Y726480D01*
X884449Y726771D01*
X884886Y726480D01*
Y725896D01*
X884449Y725604D01*
G01X915082Y735813D02*
Y718313D01*
X923816D01*
G01X939569D02*
Y735813D01*
X931490Y723271D01*
X942408D01*
G01X586529Y701163D02*
X591769D01*
G01X589149D02*
Y683663D01*
G01X586529D02*
X591769D01*
G01X600972D02*
Y701163D01*
X606649Y686580D01*
X612326Y701163D01*
Y683663D01*
G01X619782D02*
Y701163D01*
X625022D01*
X626769Y700288D01*
X628079Y698246D01*
X628516Y695913D01*
X628079Y693580D01*
X626987Y691830D01*
X625022Y690954D01*
X619782D01*
G01X640557Y677830D02*
X638374Y680746D01*
X637282Y683663D01*
Y695329D01*
X638374Y698246D01*
X640557Y701163D01*
G01X659149Y683663D02*
X657402Y683955D01*
X655874Y685121D01*
X654564Y686871D01*
X653690Y688913D01*
X653254Y691246D01*
Y693580D01*
X653690Y695913D01*
X654564Y697955D01*
X655874Y699704D01*
X657402Y700871D01*
X659149Y701163D01*
X660895Y700871D01*
X662424Y699704D01*
X663734Y697955D01*
X664608Y695913D01*
X665044Y693580D01*
Y691246D01*
X664608Y688913D01*
X663734Y686871D01*
X662424Y685121D01*
X660895Y683955D01*
X659149Y683663D01*
G01X672937D02*
Y701163D01*
G01Y692705D02*
X674029Y694163D01*
X675121Y695038D01*
X676867Y695329D01*
X678177Y695038D01*
X679706Y693871D01*
X680361Y692121D01*
Y683663D01*
G01X687599D02*
Y695329D01*
G01Y692121D02*
X688254Y693580D01*
X689346Y694746D01*
X690874Y695329D01*
X692402Y694746D01*
X693494Y693580D01*
X694149Y692121D01*
Y683663D01*
G01Y692121D02*
X694804Y693580D01*
X695895Y694746D01*
X697424Y695329D01*
X698952Y694746D01*
X700044Y693580D01*
X700699Y691830D01*
Y683663D01*
G01X712741Y677830D02*
X714924Y680746D01*
X716016Y683663D01*
Y695329D01*
X714924Y698246D01*
X712741Y701163D01*
G01X619346Y651637D02*
X620655Y650179D01*
X622184Y649305D01*
X624149Y649013D01*
X626114Y649596D01*
X627642Y650763D01*
X628734Y652804D01*
X628952Y655138D01*
X628516Y657471D01*
X627424Y658930D01*
X625895Y660096D01*
X624367Y660388D01*
X622839Y660096D01*
X620874Y658930D01*
X621529Y666513D01*
X627424D01*
G01X641649D02*
X639902Y665930D01*
X638592Y664471D01*
X637719Y662722D01*
X637064Y660388D01*
X636846Y657763D01*
X637064Y655138D01*
X637719Y652804D01*
X638592Y651054D01*
X639902Y649596D01*
X641649Y649013D01*
X643395Y649596D01*
X644706Y651054D01*
X645579Y652804D01*
X646234Y655138D01*
X646452Y657763D01*
X646234Y660388D01*
X645579Y662722D01*
X644706Y664471D01*
X643395Y665930D01*
X641649Y666513D01*
G01X659149Y648430D02*
X658712Y648721D01*
Y649305D01*
X659149Y649596D01*
X659586Y649305D01*
Y648721D01*
X659149Y648430D01*
G01X676649Y666513D02*
X674902Y665930D01*
X673592Y664471D01*
X672719Y662722D01*
X672064Y660388D01*
X671846Y657763D01*
X672064Y655138D01*
X672719Y652804D01*
X673592Y651054D01*
X674902Y649596D01*
X676649Y649013D01*
X678395Y649596D01*
X679706Y651054D01*
X680579Y652804D01*
X681234Y655138D01*
X681452Y657763D01*
X681234Y660388D01*
X680579Y662722D01*
X679706Y664471D01*
X678395Y665930D01*
X676649Y666513D01*
G01X821251Y656304D02*
X822779Y658346D01*
X824089Y659513D01*
X825836Y660096D01*
X827364Y659513D01*
X828456Y658346D01*
X829329Y656596D01*
X829547Y654555D01*
X829329Y652804D01*
X828456Y651054D01*
X827145Y649596D01*
X825617Y649013D01*
X823871Y649596D01*
X822342Y651346D01*
X821469Y653971D01*
X821251Y656888D01*
X821687Y660679D01*
X822342Y662722D01*
X823434Y664763D01*
X824962Y666221D01*
X826491Y666513D01*
X828019Y665930D01*
X829111Y664471D01*
G01X842899Y648430D02*
X842462Y648721D01*
Y649305D01*
X842899Y649596D01*
X843336Y649305D01*
Y648721D01*
X842899Y648430D01*
G01X859962Y649013D02*
X860399Y652804D01*
X861054Y656013D01*
X861927Y658930D01*
X863019Y662138D01*
X864766Y666513D01*
X856032D01*
G01X873096Y651637D02*
X874405Y650179D01*
X875934Y649305D01*
X877899Y649013D01*
X879864Y649596D01*
X881392Y650763D01*
X882484Y652804D01*
X882702Y655138D01*
X882266Y657471D01*
X881174Y658930D01*
X879645Y660096D01*
X878117Y660388D01*
X876589Y660096D01*
X874624Y658930D01*
X875279Y666513D01*
X881174D01*
G01X757599Y701163D02*
X760655Y683663D01*
X764149Y701163D01*
X767642Y683663D01*
X770699Y701163D01*
G01X779029D02*
X784269D01*
G01X781649D02*
Y683663D01*
G01X779029D02*
X784269D01*
G01X794346D02*
Y701163D01*
X798712D01*
X800459Y700288D01*
X801769Y699121D01*
X802861Y697372D01*
X803734Y695329D01*
X803952Y692413D01*
X803734Y689496D01*
X802861Y687454D01*
X801769Y685704D01*
X800459Y684538D01*
X798712Y683663D01*
X794346D01*
G01X816649Y701163D02*
Y683663D01*
G01X811627Y701163D02*
X821671D01*
G01X829564Y683663D02*
Y701163D01*
G01X838734D02*
Y683663D01*
G01Y692413D02*
X829564D01*
G01X850557Y677830D02*
X848374Y680746D01*
X847282Y683663D01*
Y695329D01*
X848374Y698246D01*
X850557Y701163D01*
G01X862599Y683663D02*
Y695329D01*
G01Y692121D02*
X863254Y693580D01*
X864346Y694746D01*
X865874Y695329D01*
X867402Y694746D01*
X868494Y693580D01*
X869149Y692121D01*
Y683663D01*
G01Y692121D02*
X869804Y693580D01*
X870895Y694746D01*
X872424Y695329D01*
X873952Y694746D01*
X875044Y693580D01*
X875699Y691830D01*
Y683663D01*
G01X886649Y695329D02*
Y683663D01*
G01Y699996D02*
X886212Y700288D01*
Y700871D01*
X886649Y701163D01*
X887086Y700871D01*
Y700288D01*
X886649Y699996D01*
G01X904149Y683663D02*
Y701163D01*
G01X918374Y685704D02*
X919466Y684538D01*
X920994Y683663D01*
X922304D01*
X923614Y684246D01*
X924487Y685121D01*
X924924Y686287D01*
X924706Y688038D01*
X923832Y688913D01*
X919902Y690663D01*
X919029Y692705D01*
X919466Y694163D01*
X920339Y695038D01*
X921649Y695329D01*
X922959Y695038D01*
X924269Y694163D01*
G01X940241Y677830D02*
X942424Y680746D01*
X943516Y683663D01*
Y695329D01*
X942424Y698246D01*
X940241Y701163D01*
G01X1004564Y651346D02*
X1006311Y649888D01*
X1008276Y649013D01*
X1010022D01*
X1011769Y649888D01*
X1013079Y651346D01*
X1013734Y653388D01*
X1013297Y655429D01*
X1012206Y657180D01*
X1010241Y658346D01*
X1007621Y658930D01*
X1006092Y660096D01*
X1005437Y662138D01*
X1005874Y664180D01*
X1006966Y665638D01*
X1008494Y666513D01*
X1010022D01*
X1011551Y665930D01*
X1012861Y664471D01*
G01X1031016Y649013D02*
X1022282D01*
Y666513D01*
X1031016D01*
G01X1027522Y658055D02*
X1022282D01*
G01X991649Y701163D02*
Y683663D01*
G01X986627Y701163D02*
X996671D01*
G01X1009149Y683663D02*
Y691538D01*
X1004782Y701163D01*
G01X1013516D02*
X1009149Y691538D01*
G01X1022282Y683663D02*
Y701163D01*
X1027522D01*
X1029269Y700288D01*
X1030579Y698246D01*
X1031016Y695913D01*
X1030579Y693580D01*
X1029487Y691830D01*
X1027522Y690954D01*
X1022282D01*
G01X1048516Y683663D02*
X1039782D01*
Y701163D01*
X1048516D01*
G01X1045022Y692705D02*
X1039782D01*
G01X1092282Y683663D02*
Y701163D01*
X1097741D01*
X1099487Y700288D01*
X1100579Y699121D01*
X1101016Y696788D01*
X1100579Y694454D01*
X1099269Y692996D01*
X1097741Y692121D01*
X1092282D01*
G01X1097741D02*
X1101016Y683663D01*
G01X1110874Y691538D02*
X1117861D01*
X1117206Y693580D01*
X1116114Y694746D01*
X1114586Y695329D01*
X1113057Y695038D01*
X1111747Y694163D01*
X1110874Y692121D01*
X1110437Y690371D01*
Y688621D01*
X1110874Y686871D01*
X1111966Y685121D01*
X1113276Y683955D01*
X1114804Y683663D01*
X1116332Y684246D01*
X1117861Y685996D01*
G01X1130339Y683663D02*
Y698538D01*
X1130776Y699996D01*
X1131649Y700871D01*
X1132959Y701163D01*
X1134269Y700580D01*
X1134924Y699121D01*
G01X1132304Y694163D02*
X1127937D01*
G01X1149149Y683080D02*
X1148712Y683371D01*
Y683955D01*
X1149149Y684246D01*
X1149586Y683955D01*
Y683371D01*
X1149149Y683080D01*
G01X1179782Y683663D02*
Y701163D01*
X1185022D01*
X1186769Y700288D01*
X1188079Y698246D01*
X1188516Y695913D01*
X1188079Y693580D01*
X1186987Y691830D01*
X1185022Y690954D01*
X1179782D01*
G01X1201649Y683663D02*
Y701163D01*
G01X1223079Y683663D02*
Y695329D01*
G01Y693288D02*
X1222206Y694454D01*
X1220895Y695038D01*
X1219367Y695329D01*
X1217839Y694746D01*
X1216529Y693580D01*
X1215655Y691830D01*
X1215219Y689496D01*
X1215655Y687163D01*
X1216529Y685413D01*
X1217839Y684246D01*
X1219367Y683663D01*
X1220895Y683955D01*
X1222206Y684829D01*
X1223079Y685996D01*
G01X1232937Y683663D02*
Y695329D01*
G01Y692413D02*
X1233811Y693871D01*
X1235121Y695038D01*
X1236867Y695329D01*
X1238395Y695038D01*
X1239706Y693871D01*
X1240361Y691830D01*
Y683663D01*
G01X1250874Y691538D02*
X1257861D01*
X1257206Y693580D01*
X1256114Y694746D01*
X1254586Y695329D01*
X1253057Y695038D01*
X1251747Y694163D01*
X1250874Y692121D01*
X1250437Y690371D01*
Y688621D01*
X1250874Y686871D01*
X1251966Y685121D01*
X1253276Y683955D01*
X1254804Y683663D01*
X1256332Y684246D01*
X1257861Y685996D01*
G01X1162282Y666513D02*
Y649013D01*
X1171016D01*
G01X1179346Y652513D02*
X1180655Y650471D01*
X1182402Y649305D01*
X1184367Y649013D01*
X1186114Y649305D01*
X1187861Y650763D01*
X1188952Y652513D01*
X1189171Y654263D01*
X1188734Y656304D01*
X1187206Y657763D01*
X1185677Y658346D01*
X1183712D01*
G01X1185677D02*
X1186987Y659221D01*
X1188079Y660679D01*
X1188516Y662429D01*
X1188079Y664180D01*
X1186987Y665638D01*
X1185022Y666513D01*
X1183057Y666221D01*
X1181092Y665054D01*
G01X1371949Y660679D02*
Y649013D01*
G01Y665346D02*
X1371512Y665638D01*
Y666221D01*
X1371949Y666513D01*
X1372386Y666221D01*
Y665638D01*
X1371949Y665346D01*
G01X1386174Y651054D02*
X1387266Y649888D01*
X1388794Y649013D01*
X1390104D01*
X1391414Y649596D01*
X1392287Y650471D01*
X1392724Y651637D01*
X1392506Y653388D01*
X1391632Y654263D01*
X1387702Y656013D01*
X1386829Y658055D01*
X1387266Y659513D01*
X1388139Y660388D01*
X1389449Y660679D01*
X1390759Y660388D01*
X1392069Y659513D01*
G01X1419427Y649013D02*
Y666513D01*
X1429471Y649013D01*
Y666513D01*
G01X1441949Y649013D02*
X1440202Y649305D01*
X1438674Y650471D01*
X1437364Y652221D01*
X1436490Y654263D01*
X1436054Y656596D01*
Y658930D01*
X1436490Y661263D01*
X1437364Y663305D01*
X1438674Y665054D01*
X1440202Y666221D01*
X1441949Y666513D01*
X1443695Y666221D01*
X1445224Y665054D01*
X1446534Y663305D01*
X1447408Y661263D01*
X1447844Y658930D01*
Y656596D01*
X1447408Y654263D01*
X1446534Y652221D01*
X1445224Y650471D01*
X1443695Y649305D01*
X1441949Y649013D01*
G01X1459449Y666513D02*
Y649013D01*
G01X1454427Y666513D02*
X1464471D01*
G01X1490737Y660679D02*
Y652513D01*
X1491611Y650471D01*
X1492921Y649305D01*
X1494449Y649013D01*
X1495977Y649305D01*
X1497287Y650471D01*
X1498161Y652513D01*
G01Y649013D02*
Y660679D01*
G01X1508674Y651054D02*
X1509766Y649888D01*
X1511294Y649013D01*
X1512604D01*
X1513914Y649596D01*
X1514787Y650471D01*
X1515224Y651637D01*
X1515006Y653388D01*
X1514132Y654263D01*
X1510202Y656013D01*
X1509329Y658055D01*
X1509766Y659513D01*
X1510639Y660388D01*
X1511949Y660679D01*
X1513259Y660388D01*
X1514569Y659513D01*
G01X1526174Y656888D02*
X1533161D01*
X1532506Y658930D01*
X1531414Y660096D01*
X1529886Y660679D01*
X1528357Y660388D01*
X1527047Y659513D01*
X1526174Y657471D01*
X1525737Y655721D01*
Y653971D01*
X1526174Y652221D01*
X1527266Y650471D01*
X1528576Y649305D01*
X1530104Y649013D01*
X1531632Y649596D01*
X1533161Y651346D01*
G01X1550879Y666513D02*
Y649013D01*
G01Y651637D02*
X1550006Y650179D01*
X1548695Y649305D01*
X1547167Y649013D01*
X1545421Y649596D01*
X1544111Y651054D01*
X1543237Y652804D01*
X1543019Y654846D01*
X1543237Y656888D01*
X1544111Y658638D01*
X1545421Y660096D01*
X1547167Y660679D01*
X1548695Y660388D01*
X1549787Y659804D01*
X1550879Y658638D01*
G01X1297146Y683080D02*
X1306752Y695913D01*
G01X1301949Y698246D02*
Y680746D01*
G01X1306752Y683080D02*
X1297146Y695913D01*
G01X1295399Y689496D02*
X1308499D01*
G01X1334111D02*
X1339787D01*
G01X1367146Y683663D02*
Y701163D01*
X1371512D01*
X1373259Y700288D01*
X1374569Y699121D01*
X1375661Y697372D01*
X1376534Y695329D01*
X1376752Y692413D01*
X1376534Y689496D01*
X1375661Y687454D01*
X1374569Y685704D01*
X1373259Y684538D01*
X1371512Y683663D01*
X1367146D01*
G01X1386174Y691538D02*
X1393161D01*
X1392506Y693580D01*
X1391414Y694746D01*
X1389886Y695329D01*
X1388357Y695038D01*
X1387047Y694163D01*
X1386174Y692121D01*
X1385737Y690371D01*
Y688621D01*
X1386174Y686871D01*
X1387266Y685121D01*
X1388576Y683955D01*
X1390104Y683663D01*
X1391632Y684246D01*
X1393161Y685996D01*
G01X1403237Y683663D02*
Y695329D01*
G01Y692413D02*
X1404111Y693871D01*
X1405421Y695038D01*
X1407167Y695329D01*
X1408695Y695038D01*
X1410006Y693871D01*
X1410661Y691830D01*
Y683663D01*
G01X1424449D02*
X1423139Y683955D01*
X1421829Y685121D01*
X1420955Y687163D01*
X1420519Y689496D01*
X1420955Y691830D01*
X1421829Y693871D01*
X1423139Y695038D01*
X1424449Y695329D01*
X1425759Y695038D01*
X1427069Y693871D01*
X1427942Y691830D01*
X1428161Y689496D01*
X1427942Y687163D01*
X1427069Y685121D01*
X1425759Y683955D01*
X1424449Y683663D01*
G01X1441949Y701163D02*
Y683663D01*
G01X1438892Y695329D02*
X1445006D01*
G01X1456174Y691538D02*
X1463161D01*
X1462506Y693580D01*
X1461414Y694746D01*
X1459886Y695329D01*
X1458357Y695038D01*
X1457047Y694163D01*
X1456174Y692121D01*
X1455737Y690371D01*
Y688621D01*
X1456174Y686871D01*
X1457266Y685121D01*
X1458576Y683955D01*
X1460104Y683663D01*
X1461632Y684246D01*
X1463161Y685996D01*
G01X1473674Y685704D02*
X1474766Y684538D01*
X1476294Y683663D01*
X1477604D01*
X1478914Y684246D01*
X1479787Y685121D01*
X1480224Y686287D01*
X1480006Y688038D01*
X1479132Y688913D01*
X1475202Y690663D01*
X1474329Y692705D01*
X1474766Y694163D01*
X1475639Y695038D01*
X1476949Y695329D01*
X1478259Y695038D01*
X1479569Y694163D01*
G01X1511949Y701163D02*
Y683663D01*
G01X1508892Y695329D02*
X1515006D01*
G01X1525737Y683663D02*
Y701163D01*
G01Y692705D02*
X1526829Y694163D01*
X1527921Y695038D01*
X1529667Y695329D01*
X1530977Y695038D01*
X1532506Y693871D01*
X1533161Y692121D01*
Y683663D01*
G01X1550879D02*
Y695329D01*
G01Y693288D02*
X1550006Y694454D01*
X1548695Y695038D01*
X1547167Y695329D01*
X1545639Y694746D01*
X1544329Y693580D01*
X1543455Y691830D01*
X1543019Y689496D01*
X1543455Y687163D01*
X1544329Y685413D01*
X1545639Y684246D01*
X1547167Y683663D01*
X1548695Y683955D01*
X1550006Y684829D01*
X1550879Y685996D01*
G01X1564449Y701163D02*
Y683663D01*
G01X1561392Y695329D02*
X1567506D01*
G01X1599449Y701163D02*
Y683663D01*
G01X1596392Y695329D02*
X1602506D01*
G01X1613237Y683663D02*
Y701163D01*
G01Y692705D02*
X1614329Y694163D01*
X1615421Y695038D01*
X1617167Y695329D01*
X1618477Y695038D01*
X1620006Y693871D01*
X1620661Y692121D01*
Y683663D01*
G01X1634449Y695329D02*
Y683663D01*
G01Y699996D02*
X1634012Y700288D01*
Y700871D01*
X1634449Y701163D01*
X1634886Y700871D01*
Y700288D01*
X1634449Y699996D01*
G01X1648674Y685704D02*
X1649766Y684538D01*
X1651294Y683663D01*
X1652604D01*
X1653914Y684246D01*
X1654787Y685121D01*
X1655224Y686287D01*
X1655006Y688038D01*
X1654132Y688913D01*
X1650202Y690663D01*
X1649329Y692705D01*
X1649766Y694163D01*
X1650639Y695038D01*
X1651949Y695329D01*
X1653259Y695038D01*
X1654569Y694163D01*
G01X1684329Y701163D02*
X1689569D01*
G01X1686949D02*
Y683663D01*
G01X1684329D02*
X1689569D01*
G01X1697899D02*
Y695329D01*
G01Y692121D02*
X1698554Y693580D01*
X1699646Y694746D01*
X1701174Y695329D01*
X1702702Y694746D01*
X1703794Y693580D01*
X1704449Y692121D01*
Y683663D01*
G01Y692121D02*
X1705104Y693580D01*
X1706195Y694746D01*
X1707724Y695329D01*
X1709252Y694746D01*
X1710344Y693580D01*
X1710999Y691830D01*
Y683663D01*
G01X1718019Y677830D02*
Y695329D01*
G01Y692705D02*
X1719111Y694163D01*
X1720202Y695038D01*
X1721949Y695329D01*
X1723477Y695038D01*
X1725006Y693580D01*
X1725661Y691538D01*
X1725879Y689496D01*
X1725661Y687454D01*
X1725006Y685413D01*
X1723695Y684246D01*
X1721949Y683663D01*
X1720421Y683955D01*
X1718892Y684829D01*
X1718019Y685996D01*
G01X1736174Y691538D02*
X1743161D01*
X1742506Y693580D01*
X1741414Y694746D01*
X1739886Y695329D01*
X1738357Y695038D01*
X1737047Y694163D01*
X1736174Y692121D01*
X1735737Y690371D01*
Y688621D01*
X1736174Y686871D01*
X1737266Y685121D01*
X1738576Y683955D01*
X1740104Y683663D01*
X1741632Y684246D01*
X1743161Y685996D01*
G01X1760879Y701163D02*
Y683663D01*
G01Y686287D02*
X1760006Y684829D01*
X1758695Y683955D01*
X1757167Y683663D01*
X1755421Y684246D01*
X1754111Y685704D01*
X1753237Y687454D01*
X1753019Y689496D01*
X1753237Y691538D01*
X1754111Y693288D01*
X1755421Y694746D01*
X1757167Y695329D01*
X1758695Y695038D01*
X1759787Y694454D01*
X1760879Y693288D01*
G01X1778379Y683663D02*
Y695329D01*
G01Y693288D02*
X1777506Y694454D01*
X1776195Y695038D01*
X1774667Y695329D01*
X1773139Y694746D01*
X1771829Y693580D01*
X1770955Y691830D01*
X1770519Y689496D01*
X1770955Y687163D01*
X1771829Y685413D01*
X1773139Y684246D01*
X1774667Y683663D01*
X1776195Y683955D01*
X1777506Y684829D01*
X1778379Y685996D01*
G01X1788237Y683663D02*
Y695329D01*
G01Y692413D02*
X1789111Y693871D01*
X1790421Y695038D01*
X1792167Y695329D01*
X1793695Y695038D01*
X1795006Y693871D01*
X1795661Y691830D01*
Y683663D01*
G01X1812942Y693871D02*
X1811414Y695038D01*
X1810104Y695329D01*
X1808357Y694746D01*
X1807047Y693580D01*
X1806174Y691538D01*
X1805955Y689496D01*
X1806174Y687454D01*
X1807047Y685704D01*
X1808357Y684246D01*
X1810104Y683663D01*
X1811632Y684246D01*
X1812942Y685413D01*
G01X1823674Y691538D02*
X1830661D01*
X1830006Y693580D01*
X1828914Y694746D01*
X1827386Y695329D01*
X1825857Y695038D01*
X1824547Y694163D01*
X1823674Y692121D01*
X1823237Y690371D01*
Y688621D01*
X1823674Y686871D01*
X1824766Y685121D01*
X1826076Y683955D01*
X1827604Y683663D01*
X1829132Y684246D01*
X1830661Y685996D01*
G01X-11811Y-26378D02*
G03X-7874Y-22441I0J3937D01*
G01X-31496Y-11378D02*
G03X-16496Y-26378I15000J0D01*
G01X0Y-18504D02*
G03X-7874I-3937J0D01*
G01X-11811Y-26378D02*
X-16496D01*
G01X-31496Y727913D02*
Y-11378D01*
G01X-7874Y-18504D02*
Y-22441D01*
G01Y20866D02*
G03X0I3937J0D01*
G01X-14607Y16741D02*
G03I-4291J0D01*
G01X-7874Y175427D02*
Y20866D01*
G01X-11608Y217029D02*
G03X-19685Y205824I3734J-11205D01*
G01X-9118Y209559D02*
G03X-11811Y205824I1244J-3735D01*
G01X-19685Y187877D02*
G03X-11608Y176672I11811J0D01*
G01X-11811Y187877D02*
G03X-9118Y184142I3937J0D01*
G01X-7874Y175427D02*
X-11609Y176672D01*
G01X-2692Y182000D02*
X-9119Y184142D01*
G01X-7874Y218273D02*
X-11609Y217029D01*
G01X-2692Y211701D02*
X-9119Y209559D01*
G01X-7874Y307086D02*
Y218273D01*
G01X-19685Y205824D02*
Y187877D01*
G01X-11811Y205824D02*
Y187877D01*
G01X0Y370079D02*
G03X-7874I-3937J0D01*
G01Y346456D02*
G03X0I3937J0D01*
G01Y307086D02*
G03X-7874I-3937J0D01*
G01Y370079D02*
Y346456D01*
G01Y409449D02*
G03X0I3937J0D01*
G01X-7874Y564010D02*
Y409449D01*
G01X-11608Y605612D02*
G03X-19685Y594406I3735J-11206D01*
G01X-9118Y598141D02*
G03X-11811Y594406I1244J-3735D01*
G01X-19685Y576459D02*
G03X-11608Y565254I11811J0D01*
G01X-11811Y576459D02*
G03X-9118Y572724I3937J0D01*
G01X-7874Y564010D02*
X-11609Y565255D01*
G01X-2692Y570582D02*
X-9119Y572725D01*
G01X-2692Y600284D02*
X-9119Y598141D01*
G01X-19685Y594406D02*
Y576459D01*
G01X-11811Y594406D02*
Y576459D01*
G01X-7874Y606856D02*
X-11609Y605611D01*
G01X-7874Y695669D02*
Y606856D01*
G01X-13215Y723144D02*
G03I-4291J0D01*
G01X-7874Y738976D02*
G03X-11811Y742913I-3937J0D01*
G01X-16496D02*
G03X-31496Y727913I0J-15000D01*
G01X-7874Y735039D02*
G03X0I3937J0D01*
G01Y695669D02*
G03X-7874I-3937J0D01*
G01X-11811Y742913D02*
X-16496D01*
G01X-7874Y738976D02*
Y735039D01*
G01X29075Y-26378D02*
G03X31044Y-24410I0J1969D01*
G01D02*
Y-788D01*
G01X0Y-22441D02*
G03X3937Y-26378I3937J0D01*
G01X0Y178265D02*
Y-22441D01*
G01X3937Y-26378D02*
X29075D01*
G01X44390Y5118D02*
G03I-2658J0D01*
G01X33012Y1181D02*
G03X31044Y-788I0J-1968D01*
G01X33012Y1181D02*
X199666D01*
G01X71407Y128987D02*
G03X76975Y134555I2784J2784D01*
G01X64567Y137457D02*
G03X65720Y134673I3938J0D01*
G01D02*
X94910Y105484D01*
G01X64567Y137457D02*
Y249131D01*
G01X-2692Y211701D02*
G03X0Y215436I-1245J3735D01*
G01Y178265D02*
G03X-2692Y182000I-3937J0D01*
G01X0Y350394D02*
Y215436D01*
G01X64567Y286302D02*
G03X67259Y282567I3937J0D01*
G01Y252866D02*
G03X64567Y249131I1245J-3735D01*
G01X73686Y280425D02*
X67259Y282567D01*
G01X64567Y286302D02*
Y350394D01*
G01X73686Y255008D02*
X67259Y252866D01*
G01X64567Y346456D02*
G03X72441I3937J0D01*
G01Y321260D02*
G03X64567I-3937J0D01*
G01X29075Y362205D02*
G03X31044Y364173I0J1969D01*
G01X0Y366142D02*
G03X3937Y362205I3937J0D01*
G01X31044Y364173D02*
Y387795D01*
G01X0Y566847D02*
Y366142D01*
G01X3937Y362205D02*
X29075D01*
G01X64567Y350394D02*
G03X60630Y354331I-3937J0D01*
G01X3937D02*
G03X0Y350394I0J-3937D01*
G01X60630Y354331D02*
X3937D01*
G01X44390Y393701D02*
G03I-2658J0D01*
G01X33012Y389764D02*
G03X31044Y387795I0J-1968D01*
G01X33012Y389764D02*
X199666D01*
G01X71407Y517570D02*
G03X76975Y523137I2784J2784D01*
G01X64567Y526040D02*
G03X65720Y523256I3938J0D01*
G01D02*
X94910Y494066D01*
G01X64567Y526040D02*
Y637713D01*
G01X-2692Y600283D02*
G03X0Y604019I-1245J3735D01*
G01Y566847D02*
G03X-2692Y570582I-3937J0D01*
G01X64567Y674885D02*
G03X67259Y671150I3937J0D01*
G01Y641448D02*
G03X64567Y637713I1245J-3735D01*
G01X73686Y669007D02*
X67259Y671150D01*
G01X64567Y674885D02*
Y738976D01*
G01X73686Y643591D02*
X67259Y641448D01*
G01X0Y738976D02*
Y604019D01*
G01X64567Y735039D02*
G03X72441I3937J0D01*
G01Y709842D02*
G03X64567I-3937J0D01*
G01Y738976D02*
G03X60630Y742913I-3937J0D01*
G01X3937D02*
G03X0Y738976I0J-3937D01*
G01X60630Y742913D02*
X3937D01*
G01X127362Y78740D02*
G03I-11023J0D01*
G01X118788Y137176D02*
G03I-4291J0D01*
G01X94791Y116738D02*
G03X89224Y111170I-2784J-2784D01*
G01X143454D02*
G03X137886Y116738I-2784J2784D01*
G01X134984Y104331D02*
G03X137768Y105484I0J3938D01*
G01X94910D02*
G03X97694Y104331I2784J2785D01*
G01X137886Y116738D02*
X133353Y112205D01*
G01X166957Y134673D02*
X137768Y105484D01*
G01X94791Y116738D02*
X99325Y112205D01*
G01X72441Y139088D02*
X76975Y134555D01*
G01X72441Y139088D02*
Y246293D01*
G01X133353Y112205D02*
X99325D01*
G01X134984Y104331D02*
X97694D01*
G01X84252Y276690D02*
G03X76175Y287895I-11811J0D01*
G01X76378Y276690D02*
G03X73686Y280425I-3937J0D01*
G01X76175Y247538D02*
G03X84252Y258743I-3734J11205D01*
G01X73686Y255008D02*
G03X76378Y258743I-1245J3735D01*
G01X76176Y287895D02*
X72441Y289140D01*
G01X84252Y258743D02*
Y276690D01*
G01X76378Y258743D02*
Y276690D01*
G01X72441Y289140D02*
Y321260D01*
G01X76176Y247538D02*
X72441Y246293D01*
G01X119874Y329366D02*
G03I-4291J0D01*
G01X76378Y354331D02*
G03X72441Y350394I0J-3937D01*
G01X76378Y354331D02*
X156299D01*
G01X72441Y346456D02*
Y350394D01*
G01X118788Y525759D02*
G03I-4291J0D01*
G01X94791Y505321D02*
G03X89224Y499753I-2784J-2784D01*
G01X143454D02*
G03X137886Y505321I-2784J2784D01*
G01D02*
X133353Y500787D01*
G01X94791Y505321D02*
X99325Y500787D01*
G01X72441Y527671D02*
X76975Y523137D01*
G01X133353Y500787D02*
X99325D01*
G01X134984Y492913D02*
G03X137768Y494066I0J3938D01*
G01X127362Y467323D02*
G03I-11023J0D01*
G01X94910Y494066D02*
G03X97694Y492913I2784J2785D01*
G01X166957Y523256D02*
X137768Y494066D01*
G01X134984Y492913D02*
X97694D01*
G01X72441Y527671D02*
Y634876D01*
G01X84252Y665272D02*
G03X76175Y676478I-11812J0D01*
G01Y636120D02*
G03X84252Y647326I-3735J11206D01*
G01X76176Y676477D02*
X72441Y677722D01*
G01X84252Y647326D02*
Y665272D01*
G01X72441Y677722D02*
Y709842D01*
G01X76176Y636121D02*
X72441Y634876D01*
G01X76378Y665272D02*
G03X73686Y669007I-3937J0D01*
G01Y643591D02*
G03X76378Y647326I-1245J3735D01*
G01D02*
Y665272D01*
G01X119874Y717948D02*
G03I-4291J0D01*
G01X76378Y742913D02*
G03X72441Y738976I0J-3937D01*
G01X76378Y742913D02*
X156299D01*
G01X72441Y735039D02*
Y738976D01*
G01X201634Y-24410D02*
G03X203603Y-26378I1968J0D01*
G01X201634Y-788D02*
Y-24410D01*
G01X203603Y-26378D02*
X228740D01*
G01X193603Y5118D02*
G03I-2658J0D01*
G01X201634Y-788D02*
G03X199666Y1181I-1969J0D01*
G01X155703Y134555D02*
G03X161271Y128987I2784J-2784D01*
G01X166957Y134673D02*
G03X168110Y137457I-2785J2784D01*
G01X160236Y139088D02*
X155703Y134555D01*
G01X160236Y246293D02*
Y139088D01*
G01X168110Y249131D02*
Y137457D01*
G01X165418Y282567D02*
G03X168110Y286302I-1245J3735D01*
G01X156502Y287895D02*
G03X148425Y276690I3734J-11205D01*
G01X158992Y280425D02*
G03X156299Y276690I1244J-3735D01*
G01X168110Y249131D02*
G03X165418Y252866I-3937J0D01*
G01X148425Y258743D02*
G03X156502Y247538I11811J0D01*
G01X156299Y258743D02*
G03X158992Y255008I3937J0D01*
G01X160236Y246293D02*
X156501Y247538D01*
G01X165418Y252866D02*
X158991Y255008D01*
G01X160236Y321260D02*
Y289140D01*
G01X168110Y350394D02*
Y286302D01*
G01X148425Y276690D02*
Y258743D01*
G01X156299Y276690D02*
Y258743D01*
G01X160236Y289140D02*
X156501Y287895D01*
G01X165418Y282567D02*
X158991Y280425D01*
G01X225227Y362205D02*
G03Y354331I0J-3937D01*
G01X207116D02*
G03Y362205I0J3937D01*
G01X160236Y346456D02*
G03X168110I3937J0D01*
G01Y321260D02*
G03X160236I-3937J0D01*
G01Y350394D02*
G03X156299Y354331I-3937J0D01*
G01X201634Y364173D02*
G03X203603Y362205I1968J0D01*
G01X201634Y387795D02*
Y364173D01*
G01X203603Y362205D02*
X228740D01*
G01X172047Y354331D02*
G03X168110Y350394I0J-3937D01*
G01X228740Y354331D02*
X172047D01*
G01X160236Y350394D02*
Y346456D01*
G01X193603Y393701D02*
G03I-2658J0D01*
G01X201634Y387795D02*
G03X199666Y389764I-1969J0D01*
G01X155703Y523137D02*
G03X161271Y517570I2784J-2783D01*
G01X160236Y527671D02*
X155703Y523137D01*
G01X166957Y523256D02*
G03X168110Y526040I-2785J2784D01*
G01Y637713D02*
Y526040D01*
G01X160236Y634876D02*
Y527671D01*
G01X156502Y676478D02*
G03X148425Y665272I3735J-11206D01*
G01Y647326D02*
G03X156502Y636120I11812J0D01*
G01X160236Y634876D02*
X156501Y636121D01*
G01X160236Y709842D02*
Y677722D01*
G01X148425Y665272D02*
Y647326D01*
G01X160236Y677722D02*
X156501Y676477D01*
G01X165418Y671150D02*
G03X168110Y674885I-1245J3735D01*
G01X158992Y669007D02*
G03X156299Y665272I1244J-3735D01*
G01X168110Y637713D02*
G03X165418Y641448I-3937J0D01*
G01X156299Y647326D02*
G03X158992Y643591I3937J0D01*
G01X165418Y641448D02*
X158991Y643591D01*
G01X168110Y738976D02*
Y674885D01*
G01X156299Y665272D02*
Y647326D01*
G01X165418Y671150D02*
X158991Y669007D01*
G01X160236Y735039D02*
G03X168110I3937J0D01*
G01Y709842D02*
G03X160236I-3937J0D01*
G01Y738976D02*
G03X156299Y742913I-3937J0D01*
G01X160236Y738976D02*
Y735039D01*
G01X172047Y742913D02*
G03X168110Y738976I0J-3937D01*
G01X228740Y742913D02*
X172047D01*
G01X236614Y-14567D02*
X244488D01*
G01X236614D02*
G03X232677Y-18504I0J-3937D01*
G01X248425D02*
G03X244488Y-14567I-3937J0D01*
G01X248425Y-22441D02*
G03X252362Y-26378I3937J0D01*
G01D02*
X309055D01*
G01X248425Y112921D02*
Y-22441D01*
G01X228740Y-26378D02*
G03X232677Y-22441I0J3937D01*
G01D02*
Y178669D01*
G01X236614Y16929D02*
X244488D01*
G01X232677Y20866D02*
G03X236614Y16929I3937J0D01*
G01X244488D02*
G03X248425Y20866I0J3937D01*
G01X246249Y145762D02*
G03X248425Y149283I-1761J3521D01*
G01Y112921D02*
G03X246249Y116442I-3937J0D01*
G01X242727Y144001D02*
G03X240551Y140480I1761J-3521D01*
G01Y121724D02*
G03X242727Y118203I3937J0D01*
G01X240551Y140480D02*
Y121724D01*
G01X242728Y118203D02*
X246249Y116442D01*
G01X242728Y144001D02*
X246249Y145762D01*
G01X248425Y350394D02*
Y149283D01*
G01X234853Y182190D02*
G03X232677Y178669I1761J-3521D01*
G01Y215031D02*
G03X234853Y211510I3937J0D01*
G01X238375Y183951D02*
G03X240551Y187472I-1761J3521D01*
G01Y206228D02*
G03X238375Y209749I-3937J0D01*
G01X240551Y187472D02*
Y206228D01*
G01X232677Y215031D02*
Y350394D01*
G01X238375Y209749D02*
X234854Y211510D01*
G01X238375Y183951D02*
X234854Y182190D01*
G01X273986Y362205D02*
G03Y354331I0J-3937D01*
G01X255876D02*
G03Y362205I0J3937D01*
G01X236614Y374016D02*
X244488D01*
G01X236614D02*
G03X232677Y370079I0J-3937D01*
G01X248425D02*
G03X244488Y374016I-3937J0D01*
G01X236614Y342519D02*
X244488D01*
G01X236614Y311023D02*
X244488D01*
G01X236614D02*
G03X232677Y307086I0J-3937D01*
G01Y346456D02*
G03X236614Y342519I3937J0D01*
G01X244488D02*
G03X248425Y346456I0J3937D01*
G01Y307086D02*
G03X244488Y311023I-3937J0D01*
G01X248425Y366142D02*
G03X252362Y362205I3937J0D01*
G01D02*
X309055D01*
G01X248425Y501504D02*
Y366142D01*
G01X228740Y362205D02*
G03X232677Y366142I0J3937D01*
G01D02*
Y567252D01*
G01X279469Y352362D02*
G03X277500Y354331I-1969J0D01*
G01X252362D02*
G03X248425Y350394I0J-3937D01*
G01X292815Y322834D02*
G03I-2657J0D01*
G01X279469Y328740D02*
G03X281437Y326771I1969J0D01*
G01X279469Y328740D02*
Y352362D01*
G01X448091Y326771D02*
X281437D01*
G01X277500Y354331D02*
X252362D01*
G01X232677Y350394D02*
G03X228740Y354331I-3937J0D01*
G01X236614Y405512D02*
X244488D01*
G01X232677Y409449D02*
G03X236614Y405512I3937J0D01*
G01X244488D02*
G03X248425Y409449I0J3937D01*
G01Y501504D02*
G03X246249Y505025I-3937J0D01*
G01X240551Y510307D02*
G03X242727Y506786I3937J0D01*
G01X240551Y529063D02*
Y510307D01*
G01X242728Y506786D02*
X246249Y505025D01*
G01Y534345D02*
G03X248425Y537866I-1761J3521D01*
G01X242727Y532584D02*
G03X240551Y529063I1761J-3521D01*
G01X248425Y738976D02*
Y537866D01*
G01X242728Y532584D02*
X246249Y534345D01*
G01X234853Y570773D02*
G03X232677Y567252I1761J-3521D01*
G01Y603614D02*
G03X234853Y600093I3937J0D01*
G01X238375Y572534D02*
G03X240551Y576055I-1761J3521D01*
G01Y594811D02*
G03X238375Y598332I-3937J0D01*
G01X240551Y576055D02*
Y594811D01*
G01X238375Y598332D02*
X234854Y600093D01*
G01X238375Y572534D02*
X234854Y570773D01*
G01X232677Y603614D02*
Y738976D01*
G01X236614Y731102D02*
X244488D01*
G01X236614Y699606D02*
X244488D01*
G01X236614D02*
G03X232677Y695669I0J-3937D01*
G01Y735039D02*
G03X236614Y731102I3937J0D01*
G01X244488D02*
G03X248425Y735039I0J3937D01*
G01Y695669D02*
G03X244488Y699606I-3937J0D01*
G01X279469Y740945D02*
G03X277500Y742913I-1968J0D01*
G01X252362D02*
G03X248425Y738976I0J-3937D01*
G01X292815Y711417D02*
G03I-2657J0D01*
G01X279469Y717323D02*
G03X281437Y715354I1969J0D01*
G01X279469Y717323D02*
Y740945D01*
G01X448091Y715354D02*
X281437D01*
G01X277500Y742913D02*
X252362D01*
G01X232677Y738976D02*
G03X228740Y742913I-3937J0D01*
G01X369811Y-1413D02*
G03I-4291J0D01*
G01X320866Y-18504D02*
G03X312992I-3937J0D01*
G01X320866Y-22441D02*
G03X324803Y-26378I3937J0D01*
G01X404725D02*
X324803D01*
G01X320866Y-22441D02*
Y-18504D01*
G01X309055Y-26378D02*
G03X312992Y-22441I0J3937D01*
G01D02*
Y41650D01*
G01Y6693D02*
G03X320866I3937J0D01*
G01X324600Y40057D02*
G03X332677Y51263I-3735J11206D01*
G01Y69209D02*
G03X324600Y80415I-11812J0D01*
G01X320866Y6693D02*
Y38813D01*
G01X332677Y51263D02*
Y69209D01*
G01X320866Y38813D02*
X324601Y40058D01*
G01X315685Y45385D02*
G03X312992Y41650I1244J-3735D01*
G01X322111Y47528D02*
G03X324803Y51263I-1245J3735D01*
G01Y69209D02*
G03X322111Y72944I-3937J0D01*
G01X324803Y51263D02*
Y69209D01*
G01X315684Y45385D02*
X322111Y47528D01*
G01X320866Y81659D02*
X324601Y80414D01*
G01X320866Y81659D02*
Y188864D01*
G01X312992Y78822D02*
G03X315685Y75087I3937J0D01*
G01X315684D02*
X322111Y72944D01*
G01X312992Y78822D02*
Y190495D01*
G01X370897Y190776D02*
G03I-4291J0D01*
G01X337649Y216782D02*
G03X343217Y211214I2784J-2784D01*
G01X325400Y193398D02*
G03X319832Y198965I-2784J2784D01*
G01X343217Y211214D02*
X347750Y215748D01*
G01X320866Y188864D02*
X325400Y193398D01*
G01X347750Y215748D02*
X381778D01*
G01X314145Y193279D02*
G03X312992Y190495I2785J-2784D01*
G01X346119Y223622D02*
G03X343335Y222469I0J-3938D01*
G01X314145Y193279D02*
X343335Y222469D01*
G01X375788Y249212D02*
G03I-11024J0D01*
G01X346119Y223622D02*
X383409D01*
G01X320866Y370079D02*
G03X312992I-3937J0D01*
G01X320866Y366142D02*
G03X324803Y362205I3937J0D01*
G01X404725D02*
X324803D01*
G01X320866Y366142D02*
Y370079D01*
G01X309055Y362205D02*
G03X312992Y366142I0J3937D01*
G01D02*
Y430233D01*
G01X369811Y387169D02*
G03I-4291J0D01*
G01X312992Y395275D02*
G03X320866I3937J0D01*
G01X324600Y428640D02*
G03X332677Y439845I-3734J11205D01*
G01X320866Y395275D02*
Y427395D01*
G01X332677Y439845D02*
Y457792D01*
G01X320866Y427395D02*
X324601Y428640D01*
G01X315685Y433968D02*
G03X312992Y430233I1244J-3735D01*
G01X322111Y436110D02*
G03X324803Y439845I-1245J3735D01*
G01D02*
Y457792D01*
G01X315684Y433968D02*
X322111Y436110D01*
G01X332677Y457792D02*
G03X324600Y468997I-11811J0D01*
G01X320866Y470242D02*
X324601Y468997D01*
G01X320866Y470242D02*
Y577447D01*
G01X312992Y467404D02*
G03X315685Y463669I3937J0D01*
G01X324803Y457792D02*
G03X322111Y461527I-3937J0D01*
G01X315684Y463669D02*
X322111Y461527D01*
G01X312992Y467404D02*
Y579078D01*
G01X370897Y579359D02*
G03I-4291J0D01*
G01X337649Y605365D02*
G03X343217Y599797I2784J-2784D01*
G01X325400Y581980D02*
G03X319832Y587548I-2784J2784D01*
G01X343217Y599797D02*
X347750Y604331D01*
G01X320866Y577447D02*
X325400Y581980D01*
G01X314145Y581862D02*
G03X312992Y579078I2785J-2784D01*
G01X314145Y581862D02*
X343335Y611051D01*
G01X347750Y604331D02*
X381778D01*
G01X346119Y612205D02*
G03X343335Y611051I1J-3937D01*
G01X375788Y637795D02*
G03I-11024J0D01*
G01X346119Y612205D02*
X383409D01*
G01X416536Y-18504D02*
G03X408662I-3937J0D01*
G01X404725Y-26378D02*
G03X408662Y-22441I0J3937D01*
G01Y-18504D02*
Y-22441D01*
G01X416536D02*
G03X420473Y-26378I3937J0D01*
G01D02*
X477166D01*
G01X416536Y41650D02*
Y-22441D01*
G01X408662Y6693D02*
G03X416536I3937J0D01*
G01X396851Y51263D02*
G03X404928Y40057I11812J0D01*
G01Y80415D02*
G03X396851Y69209I3735J-11206D01*
G01X404927Y40058D02*
X408662Y38813D01*
G01X396851Y69209D02*
Y51263D01*
G01X408662Y38813D02*
Y6693D01*
G01X416536Y41650D02*
G03X413843Y45385I-3937J0D01*
G01X404725Y51263D02*
G03X407417Y47528I3937J0D01*
G01Y72944D02*
G03X404725Y69209I1245J-3735D01*
G01X407417Y47528D02*
X413844Y45385D01*
G01X404725Y69209D02*
Y51263D01*
G01X408662Y188864D02*
Y81659D01*
G01X404927Y80414D02*
X408662Y81659D01*
G01X413843Y75087D02*
G03X416536Y78822I-1244J3735D01*
G01Y190495D02*
Y78822D01*
G01X407417Y72944D02*
X413844Y75087D01*
G01X409696Y198965D02*
G03X404128Y193398I-2784J-2783D01*
G01X386311Y211214D02*
G03X391879Y216782I2784J2784D01*
G01X386311Y211214D02*
X381778Y215748D01*
G01X408662Y188864D02*
X404128Y193398D01*
G01X386193Y222469D02*
G03X383409Y223622I-2784J-2785D01*
G01X416536Y190495D02*
G03X415383Y193279I-3938J0D01*
G01D02*
X386193Y222469D01*
G01X416536Y370079D02*
G03X408662I-3937J0D01*
G01X404725Y362205D02*
G03X408662Y366142I0J3937D01*
G01Y370079D02*
Y366142D01*
G01X416536D02*
G03X420473Y362205I3937J0D01*
G01D02*
X477166D01*
G01X416536Y430233D02*
Y366142D01*
G01X442028Y322834D02*
G03I-2658J0D01*
G01X448091Y326771D02*
G03X450059Y328740I0J1968D01*
G01X452028Y354331D02*
G03X450059Y352362I0J-1969D01*
G01D02*
Y328740D01*
G01X408662Y395275D02*
G03X416536I3937J0D01*
G01X396851Y439845D02*
G03X404928Y428640I11811J0D01*
G01X404927D02*
X408662Y427395D01*
G01X396851Y457792D02*
Y439845D01*
G01X408662Y427395D02*
Y395275D01*
G01X416536Y430233D02*
G03X413843Y433968I-3937J0D01*
G01X404725Y439845D02*
G03X407417Y436110I3937J0D01*
G01D02*
X413844Y433968D01*
G01X404725Y457792D02*
Y439845D01*
G01X404928Y468997D02*
G03X396851Y457792I3734J-11205D01*
G01X408662Y577447D02*
Y470242D01*
G01X404927Y468997D02*
X408662Y470242D01*
G01X413843Y463669D02*
G03X416536Y467404I-1244J3735D01*
G01X407417Y461527D02*
G03X404725Y457792I1245J-3735D01*
G01X416536Y579078D02*
Y467404D01*
G01X407417Y461527D02*
X413844Y463669D01*
G01X409696Y587548D02*
G03X404128Y581980I-2784J-2784D01*
G01X386311Y599797D02*
G03X391879Y605365I2784J2784D01*
G01X386311Y599797D02*
X381778Y604331D01*
G01X408662Y577447D02*
X404128Y581980D01*
G01X416536Y579078D02*
G03X415383Y581862I-3938J0D01*
G01D02*
X386193Y611051D01*
G01D02*
G03X383409Y612205I-2785J-2783D01*
G01X442028Y711417D02*
G03I-2658J0D01*
G01X448091Y715354D02*
G03X450059Y717323I0J1968D01*
G01X452028Y742913D02*
G03X450059Y740945I0J-1969D01*
G01D02*
Y717323D01*
G01X488977Y-22441D02*
G03X492914Y-26378I3937J0D01*
G01X497599D02*
G03X512599Y-11378I0J15000D01*
G01X488977Y-18504D02*
G03X481103I-3937J0D01*
G01X492914Y-26378D02*
X497599D01*
G01X512599Y-11378D02*
Y455139D01*
G01X488977Y-22441D02*
Y-18504D01*
G01X477166Y-26378D02*
G03X481103Y-22441I0J3937D01*
G01D02*
Y112517D01*
G01Y20866D02*
G03X488977I3937J0D01*
G01D02*
Y109679D01*
G01X492711Y110924D02*
G03X500788Y122129I-3734J11205D01*
G01Y140076D02*
G03X492711Y151281I-11811J0D01*
G01X488977Y109679D02*
X492712Y110924D01*
G01X500788Y122129D02*
Y140076D01*
G01X483795Y116252D02*
G03X481103Y112517I1245J-3735D01*
G01Y149688D02*
G03X483795Y145953I3937J0D01*
G01X490221Y118394D02*
G03X492914Y122129I-1244J3735D01*
G01Y140076D02*
G03X490221Y143811I-3937J0D01*
G01X483795Y145953D02*
X490222Y143811D01*
G01X483795Y116251D02*
X490222Y118394D01*
G01X492914Y122129D02*
Y140076D01*
G01X488977Y152525D02*
X492712Y151280D01*
G01X488977Y152525D02*
Y307086D01*
G01X481103Y149688D02*
Y350394D01*
G01X488977Y307086D02*
G03X481103I-3937J0D01*
G01Y346456D02*
G03X488977I3937J0D01*
G01Y370079D02*
G03X481103I-3937J0D01*
G01X488977Y346456D02*
Y370079D01*
G01X477166Y362205D02*
G03X481103Y366142I0J3937D01*
G01D02*
Y501099D01*
G01Y350394D02*
G03X477166Y354331I-3937J0D01*
G01D02*
X452028D01*
G01X481103Y409449D02*
G03X488977I3937J0D01*
G01D02*
Y498262D01*
G01X512599Y463013D02*
G03Y455139I0J-3937D01*
G01Y463013D02*
Y727913D01*
G01X492711Y499506D02*
G03X500788Y510711I-3734J11205D01*
G01X488977Y498262D02*
X492712Y499507D01*
G01X500788Y510711D02*
Y528658D01*
G01X483795Y504834D02*
G03X481103Y501099I1245J-3735D01*
G01X490221Y506976D02*
G03X492914Y510711I-1244J3735D01*
G01X483795Y504834D02*
X490222Y506976D01*
G01X492914Y510711D02*
Y528658D01*
G01X500788D02*
G03X492711Y539863I-11811J0D01*
G01X488977Y541108D02*
X492712Y539863D01*
G01X488977Y541108D02*
Y695669D01*
G01X481103Y538271D02*
G03X483795Y534535I3937J-1D01*
G01X492914Y528658D02*
G03X490221Y532393I-3937J0D01*
G01X483795Y534536D02*
X490222Y532393D01*
G01X481103Y538271D02*
Y738976D01*
G01X499107Y713716D02*
G03I-4291J0D01*
G01X492914Y742913D02*
G03X488977Y738976I0J-3937D01*
G01X512599Y727913D02*
G03X497599Y742913I-15000J0D01*
G01X488977Y695669D02*
G03X481103I-3937J0D01*
G01Y735039D02*
G03X488977I3937J0D01*
G01X492914Y742913D02*
X497599D01*
G01X488977Y735039D02*
Y738976D01*
G01X481103D02*
G03X477166Y742913I-3937J0D01*
G01D02*
X452028D01*
G54D12*
G01X88700Y25600D02*
X58700Y55600D01*
G01X41800Y44200D02*
X48000Y38000D01*
G01X39700Y44200D02*
X41800D01*
G01X30088Y53812D02*
X39700Y44200D01*
G01X30088Y65594D02*
Y53812D01*
G01X19850Y75832D02*
X30088Y65594D01*
G01X71562Y20838D02*
X76900Y15500D01*
G01X55400Y20838D02*
X71562D01*
G01X53276Y22962D02*
X55400Y20838D01*
G01X53276Y37724D02*
Y22962D01*
G01X44200Y46800D02*
X53276Y37724D01*
G01X42984Y46800D02*
X44200D01*
G01X42922Y46862D02*
X42984Y46800D01*
G01X42163Y46862D02*
X42922D01*
G01X42150Y46875D02*
X42163Y46862D01*
G01X41225Y46875D02*
X42150D01*
G01X38000Y50100D02*
X41225Y46875D01*
G01X38000Y54700D02*
Y50100D01*
G01X36100Y56600D02*
X38000Y54700D01*
G01X36100Y63500D02*
Y56600D01*
G01X23100Y76500D02*
X36100Y63500D01*
G01X14927Y83177D02*
X9000Y77250D01*
G01X14927Y149848D02*
Y83177D01*
G01X44200Y109200D02*
X46200Y111200D01*
G01X44200Y101787D02*
Y109200D01*
G01X40900Y98487D02*
X44200Y101787D01*
G01X40900Y88400D02*
Y98487D01*
G01X19850Y92113D02*
Y75832D01*
G01X19763Y92200D02*
X19850Y92113D01*
G01X19763Y96137D02*
Y92200D01*
G01X18102Y97798D02*
X19763Y96137D01*
G01X18102Y149239D02*
Y97798D01*
G01X11752Y84002D02*
X9000Y81250D01*
G01X11752Y151164D02*
Y84002D01*
G01X23100Y99960D02*
Y76500D01*
G01X23093Y99967D02*
X23100Y99960D01*
G01X20866Y163708D02*
X20539Y163381D01*
G01X20866Y180894D02*
Y163708D01*
G01X13181Y188579D02*
X20866Y180894D01*
G01X13181Y215014D02*
Y188579D01*
G01X16584Y218417D02*
X13181Y215014D01*
G01X30939Y218417D02*
X16584D01*
G01X33148Y220626D02*
X30939Y218417D01*
G01X33148Y223305D02*
Y220626D01*
G01X38189Y228346D02*
X33148Y223305D01*
G01X20539Y155460D02*
X14927Y149848D01*
G01X20539Y163381D02*
Y155460D01*
G01X23701Y154838D02*
X18102Y149239D01*
G01X23701Y181843D02*
Y154838D01*
G01X15856Y189688D02*
X23701Y181843D01*
G01X15856Y202216D02*
Y189688D01*
G01X15857Y202217D02*
X15856Y202216D01*
G01X15857Y202417D02*
Y202217D01*
G01X16253Y181723D02*
Y180320D01*
G01X10506Y187470D02*
X16253Y181723D01*
G01X10506Y216123D02*
Y187470D01*
G01X21524Y227141D02*
X10506Y216123D01*
G01X38189Y220472D02*
X41872Y224155D01*
G01X17851Y157263D02*
X11752Y151164D01*
G01X17851Y165535D02*
Y157263D01*
G01X18191Y165875D02*
X17851Y165535D01*
G01X18191Y178382D02*
Y165875D01*
G01X16253Y180320D02*
X18191Y178382D01*
G01X30487Y227141D02*
X21524D01*
G01X35116Y231770D02*
X30487Y227141D01*
G01X40595Y231770D02*
X35116D01*
G01X41872Y230493D02*
X40595Y231770D01*
G01X41872Y224155D02*
Y230493D01*
G01X99200Y25600D02*
X88700D01*
G01X99300Y25700D02*
X99200Y25600D01*
G01X129800Y12600D02*
X126742Y15658D01*
G01X135600Y12600D02*
X129800D01*
G01X139838Y16838D02*
X135600Y12600D01*
G01X213038Y16838D02*
X139838D01*
G01X125700Y26500D02*
X176400D01*
G01X136439Y31761D02*
X151561D01*
G01X95600Y60800D02*
X100100Y56300D01*
G01X82200Y60800D02*
X95600D01*
G01X226500Y30300D02*
X213038Y16838D01*
G01X176400Y26500D02*
X208900Y59000D01*
G01X202860Y71660D02*
X204340D01*
G01X166600Y35400D02*
X202860Y71660D01*
G01X155200Y35400D02*
X166600D01*
G01X151561Y31761D02*
X155200Y35400D01*
G01X177122Y118203D02*
Y186545D01*
G01X160794Y101875D02*
X177122Y118203D01*
G01X160794Y86162D02*
Y101875D01*
G01X220200Y151000D02*
X226500Y144700D01*
G01X193500Y114800D02*
X190900Y112200D01*
G01X193500Y135835D02*
Y114800D01*
G01X171722Y120917D02*
Y189673D01*
G01X154935Y104130D02*
X171722Y120917D01*
G01X154935Y81334D02*
Y104130D01*
G01X156891Y79378D02*
X154935Y81334D01*
G01X184726Y106300D02*
X171263Y92837D01*
G01X184900Y106300D02*
X184726D01*
G01X174397Y119808D02*
Y187880D01*
G01X157755Y103166D02*
X174397Y119808D01*
G01X157755Y84047D02*
Y103166D01*
G01X159711Y82091D02*
X157755Y84047D01*
G01X212713Y221411D02*
Y230567D01*
G01X212181Y220879D02*
X212713Y221411D01*
G01X212181Y203009D02*
Y220879D01*
G01X200957Y191785D02*
X212181Y203009D01*
G01X182362Y191785D02*
X200957D01*
G01X177122Y186545D02*
X182362Y191785D01*
G01X206831Y223097D02*
X207750Y224016D01*
G01X206831Y207310D02*
Y223097D01*
G01X196793Y197272D02*
X206831Y207310D01*
G01X179321Y197272D02*
X196793D01*
G01X171722Y189673D02*
X179321Y197272D01*
G01X210038Y222520D02*
Y229458D01*
G01X209506Y221988D02*
X210038Y222520D01*
G01X209506Y206201D02*
Y221988D01*
G01X197765Y194460D02*
X209506Y206201D01*
G01X180977Y194460D02*
X197765D01*
G01X174397Y187880D02*
X180977Y194460D01*
G01X198426Y220472D02*
X193280Y225618D01*
G01X207060Y236220D02*
X198426D01*
G01X212713Y230567D02*
X207060Y236220D01*
G01X203420Y228346D02*
X207750Y224016D01*
G01X198426Y228346D02*
X203420D01*
G01X210038Y229458D02*
X209506Y229990D01*
G01X207301Y232195D02*
X209506Y229990D01*
G01X196923Y232195D02*
X207301D01*
G01X193280Y228552D02*
X196923Y232195D01*
G01X193280Y225618D02*
Y228552D01*
G01X226500Y144700D02*
Y30300D01*
M02*
